(kicad_pcb
	(version 20260206)
	(generator "pcbnew")
	(generator_version "10.0")
	(general
		(thickness 1.6)
		(legacy_teardrops no)
	)
	(paper "A4")
	(title_block
		(title "Wiwynn_Tioga_Pass_MB.brd")
		(comment 1 "Tioga Pass / footprint 858 of 4770 (J4B2), pads 1-122 of 122")
	)
	(layers
		(0 "F.Cu" signal "TOP")
		(4 "In1.Cu" signal "L2GND")
		(6 "In2.Cu" signal "L3")
		(8 "In3.Cu" signal "L4GND")
		(10 "In4.Cu" signal "L5")
		(12 "In5.Cu" signal "L6GND")
		(14 "In6.Cu" signal "L7VCC")
		(16 "In7.Cu" signal "L8VCC")
		(18 "In8.Cu" signal "L9GND")
		(20 "In9.Cu" signal "L10")
		(22 "In10.Cu" signal "L11GND")
		(24 "In11.Cu" signal "L12")
		(26 "In12.Cu" signal "L13GND")
		(2 "B.Cu" signal "BOTTOM")
		(9 "F.Adhes" user "F.Adhesive")
		(11 "B.Adhes" user "B.Adhesive")
		(13 "F.Paste" user "Package Geometry/Pastemask Top")
		(15 "B.Paste" user "Package Geometry/Pastemask Bottom")
		(5 "F.SilkS" user "Ref Des/Silkscreen Top")
		(7 "B.SilkS" user "Ref Des/Silkscreen Bottom")
		(1 "F.Mask" user "Board Geometry/Soldermask Top")
		(3 "B.Mask" user "Board Geometry/Soldermask Bottom")
		(17 "Dwgs.User" user "User.Drawings")
		(19 "Cmts.User" user "User.Comments")
		(21 "Eco1.User" user "User.Eco1")
		(23 "Eco2.User" user "User.Eco2")
		(25 "Edge.Cuts" user "Board Geometry/Outline")
		(27 "Margin" user)
		(31 "F.CrtYd" user "Package Geometry/Place Bound Top")
		(29 "B.CrtYd" user "Package Geometry/Place Bound Bottom")
		(35 "F.Fab" user "Ref Des/Assembly Top")
		(33 "B.Fab" user "Ref Des/Assembly Bottom")
	)
	(footprint ""
		(layer "F.Cu")
		(at 164.615114 -115.55095 90)
		(property "Reference" "J4B2"
			(at -3.59283 -5.018024 90)
			(unlocked yes)
			(layer "F.SilkS")
			(effects
				(font
					(size 0.7874 0.5842)
					(thickness 0.1524)
				)
			)
		)
		(property "Value" ""
			(at 0 0 90)
			(layer "F.Fab")
			(effects
				(font
					(size 1.27 1.27)
				)
			)
		)
		(duplicate_pad_numbers_are_jumpers no)
		(pad "" np_thru_hole circle
			(at -3.175 26.5557 90)
			(size 0.254 0.254)
			(drill 1.27)
			(layers "*.Cu" "*.Mask")
			(clearance 0.8255)
			(thermal_gap 0.8255)
		)
		(pad "" np_thru_hole circle
			(at -0.127 -2.4257 90)
			(size 0.254 0.254)
			(drill 1.27)
			(layers "*.Cu" "*.Mask")
			(clearance 0.8255)
			(thermal_gap 0.8255)
		)
		(pad "A1" smd circle
			(at 0 0 90)
			(size 0.635 0.635)
			(layers "F.Cu" "F.Mask" "F.Paste")
			(net "P12V_STBY")
		)
		(pad "A2" smd circle
			(at 0 1.27 90)
			(size 0.635 0.635)
			(layers "F.Cu" "F.Mask" "F.Paste")
			(net "P12V_STBY")
		)
		(pad "A3" smd circle
			(at 0 2.54 90)
			(size 0.635 0.635)
			(layers "F.Cu" "F.Mask" "F.Paste")
			(net "P12V_STBY")
		)
		(pad "A4" smd circle
			(at 0 3.81 90)
			(size 0.635 0.635)
			(layers "F.Cu" "F.Mask" "F.Paste")
			(net "P12V_STBY")
		)
		(pad "A5" smd circle
			(at 0 5.08 90)
			(size 0.635 0.635)
			(layers "F.Cu" "F.Mask" "F.Paste")
			(net "P12V_STBY")
		)
		(pad "A6" smd circle
			(at 0 6.35 90)
			(size 0.635 0.635)
			(layers "F.Cu" "F.Mask" "F.Paste")
			(net "P12V_STBY")
		)
		(pad "A7" smd circle
			(at 0 7.62 90)
			(size 0.635 0.635)
			(layers "F.Cu" "F.Mask" "F.Paste")
			(net "P12V_STBY")
		)
		(pad "A8" smd circle
			(at 0 8.89 90)
			(size 0.635 0.635)
			(layers "F.Cu" "F.Mask" "F.Paste")
			(net "P12V_STBY")
		)
		(pad "A9" smd circle
			(at 0 10.16 90)
			(size 0.635 0.635)
			(layers "F.Cu" "F.Mask" "F.Paste")
			(net "GND")
		)
		(pad "A10" smd circle
			(at 0 11.43 90)
			(size 0.635 0.635)
			(layers "F.Cu" "F.Mask" "F.Paste")
			(net "GND")
		)
		(pad "A11" smd circle
			(at 0 12.7 90)
			(size 0.635 0.635)
			(layers "F.Cu" "F.Mask" "F.Paste")
			(net "P3V3_STBY")
		)
		(pad "A12" smd circle
			(at 0 13.97 90)
			(size 0.635 0.635)
			(layers "F.Cu" "F.Mask" "F.Paste")
			(net "GND")
		)
		(pad "A13" smd circle
			(at 0 15.24 90)
			(size 0.635 0.635)
			(layers "F.Cu" "F.Mask" "F.Paste")
			(net "P5V_STBY")
		)
		(pad "A14" smd circle
			(at 0 16.51 90)
			(size 0.635 0.635)
			(layers "F.Cu" "F.Mask" "F.Paste")
			(net "GND")
		)
		(pad "A15" smd circle
			(at 0 17.78 90)
			(size 0.635 0.635)
			(layers "F.Cu" "F.Mask" "F.Paste")
			(net "FM_P1V8MCP_CPU1_EN")
		)
		(pad "A16" smd circle
			(at 0 19.05 90)
			(size 0.635 0.635)
			(layers "F.Cu" "F.Mask" "F.Paste")
			(net "FM_PVCCIOMCP_CPU1_EN")
		)
		(pad "A17" smd circle
			(at 0 20.32 90)
			(size 0.635 0.635)
			(layers "F.Cu" "F.Mask" "F.Paste")
			(net "GND")
		)
		(pad "A18" smd circle
			(at 0 21.59 90)
			(size 0.635 0.635)
			(layers "F.Cu" "F.Mask" "F.Paste")
			(net "SMB_VR_STBY_LVC3_SCL")
		)
		(pad "A19" smd circle
			(at 0 22.86 90)
			(size 0.635 0.635)
			(layers "F.Cu" "F.Mask" "F.Paste")
			(net "SVID_ALERT0_CPU1_R_N")
		)
		(pad "A20" smd circle
			(at 0 24.13 90)
			(size 0.635 0.635)
			(layers "F.Cu" "F.Mask" "F.Paste")
			(net "SVID_CLK0_CPU1_R")
		)
		(pad "B1" smd circle
			(at -1.27 0 90)
			(size 0.635 0.635)
			(layers "F.Cu" "F.Mask" "F.Paste")
			(net "P12V_STBY")
		)
		(pad "B2" smd circle
			(at -1.27 1.27 90)
			(size 0.635 0.635)
			(layers "F.Cu" "F.Mask" "F.Paste")
			(net "P12V_STBY")
		)
		(pad "B3" smd circle
			(at -1.27 2.54 90)
			(size 0.635 0.635)
			(layers "F.Cu" "F.Mask" "F.Paste")
			(net "P12V_STBY")
		)
		(pad "B4" smd circle
			(at -1.27 3.81 90)
			(size 0.635 0.635)
			(layers "F.Cu" "F.Mask" "F.Paste")
			(net "P12V_STBY")
		)
		(pad "B5" smd circle
			(at -1.27 5.08 90)
			(size 0.635 0.635)
			(layers "F.Cu" "F.Mask" "F.Paste")
			(net "P12V_STBY")
		)
		(pad "B6" smd circle
			(at -1.27 6.35 90)
			(size 0.635 0.635)
			(layers "F.Cu" "F.Mask" "F.Paste")
			(net "P12V_STBY")
		)
		(pad "B7" smd circle
			(at -1.27 7.62 90)
			(size 0.635 0.635)
			(layers "F.Cu" "F.Mask" "F.Paste")
			(net "P12V_STBY")
		)
		(pad "B8" smd circle
			(at -1.27 8.89 90)
			(size 0.635 0.635)
			(layers "F.Cu" "F.Mask" "F.Paste")
			(net "P12V_STBY")
		)
		(pad "B9" smd circle
			(at -1.27 10.16 90)
			(size 0.635 0.635)
			(layers "F.Cu" "F.Mask" "F.Paste")
			(net "GND")
		)
		(pad "B10" smd circle
			(at -1.27 11.43 90)
			(size 0.635 0.635)
			(layers "F.Cu" "F.Mask" "F.Paste")
			(net "GND")
		)
		(pad "B11" smd circle
			(at -1.27 12.7 90)
			(size 0.635 0.635)
			(layers "F.Cu" "F.Mask" "F.Paste")
			(net "P3V3_STBY")
		)
		(pad "B12" smd circle
			(at -1.27 13.97 90)
			(size 0.635 0.635)
			(layers "F.Cu" "F.Mask" "F.Paste")
			(net "GND")
		)
		(pad "B13" smd circle
			(at -1.27 15.24 90)
			(size 0.635 0.635)
			(layers "F.Cu" "F.Mask" "F.Paste")
			(net "P5V_STBY")
		)
		(pad "B14" smd circle
			(at -1.27 16.51 90)
			(size 0.635 0.635)
			(layers "F.Cu" "F.Mask" "F.Paste")
			(net "GND")
		)
		(pad "B15" smd circle
			(at -1.27 17.78 90)
			(size 0.635 0.635)
			(layers "F.Cu" "F.Mask" "F.Paste")
			(net "PWRGD_P1V8MCP_CPU1")
		)
		(pad "B16" smd circle
			(at -1.27 19.05 90)
			(size 0.635 0.635)
			(layers "F.Cu" "F.Mask" "F.Paste")
			(net "PWRGD_PVCCIOMCP_CPU1")
		)
		(pad "B17" smd circle
			(at -1.27 20.32 90)
			(size 0.635 0.635)
			(layers "F.Cu" "F.Mask" "F.Paste")
			(net "GND")
		)
		(pad "B18" smd circle
			(at -1.27 21.59 90)
			(size 0.635 0.635)
			(layers "F.Cu" "F.Mask" "F.Paste")
			(net "SMB_VR_STBY_LVC3_SDA")
		)
		(pad "B19" smd circle
			(at -1.27 22.86 90)
			(size 0.635 0.635)
			(layers "F.Cu" "F.Mask" "F.Paste")
			(net "SVID_ALERT1_CPU1_R_N")
		)
		(pad "B20" smd circle
			(at -1.27 24.13 90)
			(size 0.635 0.635)
			(layers "F.Cu" "F.Mask" "F.Paste")
			(net "SVID_DIO0_CPU1_R")
		)
		(pad "C1" smd circle
			(at -2.54 0 90)
			(size 0.635 0.635)
			(layers "F.Cu" "F.Mask" "F.Paste")
			(net "GND")
		)
		(pad "C2" smd circle
			(at -2.54 1.27 90)
			(size 0.635 0.635)
			(layers "F.Cu" "F.Mask" "F.Paste")
			(net "GND")
		)
		(pad "C3" smd circle
			(at -2.54 2.54 90)
			(size 0.635 0.635)
			(layers "F.Cu" "F.Mask" "F.Paste")
			(net "GND")
		)
		(pad "C4" smd circle
			(at -2.54 3.81 90)
			(size 0.635 0.635)
			(layers "F.Cu" "F.Mask" "F.Paste")
			(net "GND")
		)
		(pad "C5" smd circle
			(at -2.54 5.08 90)
			(size 0.635 0.635)
			(layers "F.Cu" "F.Mask" "F.Paste")
			(net "GND")
		)
		(pad "C6" smd circle
			(at -2.54 6.35 90)
			(size 0.635 0.635)
			(layers "F.Cu" "F.Mask" "F.Paste")
			(net "GND")
		)
		(pad "C7" smd circle
			(at -2.54 7.62 90)
			(size 0.635 0.635)
			(layers "F.Cu" "F.Mask" "F.Paste")
			(net "GND")
		)
		(pad "C8" smd circle
			(at -2.54 8.89 90)
			(size 0.635 0.635)
			(layers "F.Cu" "F.Mask" "F.Paste")
			(net "GND")
		)
		(pad "C9" smd circle
			(at -2.54 10.16 90)
			(size 0.635 0.635)
			(layers "F.Cu" "F.Mask" "F.Paste")
			(net "GND")
		)
		(pad "C10" smd circle
			(at -2.54 11.43 90)
			(size 0.635 0.635)
			(layers "F.Cu" "F.Mask" "F.Paste")
			(net "GND")
		)
		(pad "C11" smd circle
			(at -2.54 12.7 90)
			(size 0.635 0.635)
			(layers "F.Cu" "F.Mask" "F.Paste")
			(net "P3V3_STBY")
		)
		(pad "C12" smd circle
			(at -2.54 13.97 90)
			(size 0.635 0.635)
			(layers "F.Cu" "F.Mask" "F.Paste")
			(net "GND")
		)
		(pad "C13" smd circle
			(at -2.54 15.24 90)
			(size 0.635 0.635)
			(layers "F.Cu" "F.Mask" "F.Paste")
			(net "P5V_STBY")
		)
		(pad "C14" smd circle
			(at -2.54 16.51 90)
			(size 0.635 0.635)
			(layers "F.Cu" "F.Mask" "F.Paste")
			(net "GND")
		)
		(pad "C15" smd circle
			(at -2.54 17.78 90)
			(size 0.635 0.635)
			(layers "F.Cu" "F.Mask" "F.Paste")
			(net "GND")
		)
		(pad "C16" smd circle
			(at -2.54 19.05 90)
			(size 0.635 0.635)
			(layers "F.Cu" "F.Mask" "F.Paste")
			(net "GND")
		)
		(pad "C17" smd circle
			(at -2.54 20.32 90)
			(size 0.635 0.635)
			(layers "F.Cu" "F.Mask" "F.Paste")
			(net "PVCCIOMCP_CPU1")
		)
		(pad "C18" smd circle
			(at -2.54 21.59 90)
			(size 0.635 0.635)
			(layers "F.Cu" "F.Mask" "F.Paste")
			(net "PVCCIOMCP_CPU1")
		)
		(pad "C19" smd circle
			(at -2.54 22.86 90)
			(size 0.635 0.635)
			(layers "F.Cu" "F.Mask" "F.Paste")
			(net "PVCCIOMCP_CPU1")
		)
		(pad "C20" smd circle
			(at -2.54 24.13 90)
			(size 0.635 0.635)
			(layers "F.Cu" "F.Mask" "F.Paste")
			(net "FM_PVCCMCP_CPU1_EN")
		)
		(pad "D1" smd circle
			(at -3.81 0 90)
			(size 0.635 0.635)
			(layers "F.Cu" "F.Mask" "F.Paste")
			(net "P3V3")
		)
		(pad "D2" smd circle
			(at -3.81 1.27 90)
			(size 0.635 0.635)
			(layers "F.Cu" "F.Mask" "F.Paste")
			(net "GND")
		)
		(pad "D3" smd circle
			(at -3.81 2.54 90)
			(size 0.635 0.635)
			(layers "F.Cu" "F.Mask" "F.Paste")
			(net "GND")
		)
		(pad "D4" smd circle
			(at -3.81 3.81 90)
			(size 0.635 0.635)
			(layers "F.Cu" "F.Mask" "F.Paste")
			(net "GND")
		)
		(pad "D5" smd circle
			(at -3.81 5.08 90)
			(size 0.635 0.635)
			(layers "F.Cu" "F.Mask" "F.Paste")
			(net "GND")
		)
		(pad "D6" smd circle
			(at -3.81 6.35 90)
			(size 0.635 0.635)
			(layers "F.Cu" "F.Mask" "F.Paste")
			(net "GND")
		)
		(pad "D7" smd circle
			(at -3.81 7.62 90)
			(size 0.635 0.635)
			(layers "F.Cu" "F.Mask" "F.Paste")
			(net "GND")
		)
		(pad "D8" smd circle
			(at -3.81 8.89 90)
			(size 0.635 0.635)
			(layers "F.Cu" "F.Mask" "F.Paste")
			(net "GND")
		)
		(pad "D9" smd circle
			(at -3.81 10.16 90)
			(size 0.635 0.635)
			(layers "F.Cu" "F.Mask" "F.Paste")
			(net "GND")
		)
		(pad "D10" smd circle
			(at -3.81 11.43 90)
			(size 0.635 0.635)
			(layers "F.Cu" "F.Mask" "F.Paste")
			(net "GND")
		)
		(pad "D11" smd circle
			(at -3.81 12.7 90)
			(size 0.635 0.635)
			(layers "F.Cu" "F.Mask" "F.Paste")
			(net "GND")
		)
		(pad "D12" smd circle
			(at -3.81 13.97 90)
			(size 0.635 0.635)
			(layers "F.Cu" "F.Mask" "F.Paste")
			(net "GND")
		)
		(pad "D13" smd circle
			(at -3.81 15.24 90)
			(size 0.635 0.635)
			(layers "F.Cu" "F.Mask" "F.Paste")
			(net "GND")
		)
		(pad "D14" smd circle
			(at -3.81 16.51 90)
			(size 0.635 0.635)
			(layers "F.Cu" "F.Mask" "F.Paste")
			(net "GND")
		)
		(pad "D15" smd circle
			(at -3.81 17.78 90)
			(size 0.635 0.635)
			(layers "F.Cu" "F.Mask" "F.Paste")
			(net "GND")
		)
		(pad "D16" smd circle
			(at -3.81 19.05 90)
			(size 0.635 0.635)
			(layers "F.Cu" "F.Mask" "F.Paste")
			(net "GND")
		)
		(pad "D17" smd circle
			(at -3.81 20.32 90)
			(size 0.635 0.635)
			(layers "F.Cu" "F.Mask" "F.Paste")
			(net "PVCCIOMCP_CPU1")
		)
		(pad "D18" smd circle
			(at -3.81 21.59 90)
			(size 0.635 0.635)
			(layers "F.Cu" "F.Mask" "F.Paste")
			(net "PVCCIOMCP_CPU1")
		)
		(pad "D19" smd circle
			(at -3.81 22.86 90)
			(size 0.635 0.635)
			(layers "F.Cu" "F.Mask" "F.Paste")
			(net "PVCCIOMCP_CPU1")
		)
		(pad "D20" smd circle
			(at -3.81 24.13 90)
			(size 0.635 0.635)
			(layers "F.Cu" "F.Mask" "F.Paste")
			(net "PWRGD_PVCCMCP_CPU1")
		)
		(pad "E1" smd circle
			(at -5.08 0 90)
			(size 0.635 0.635)
			(layers "F.Cu" "F.Mask" "F.Paste")
			(net "FM_CPU1_VRM_322M_156M_OSC_EN")
		)
		(pad "E2" smd circle
			(at -5.08 1.27 90)
			(size 0.635 0.635)
			(layers "F.Cu" "F.Mask" "F.Paste")
			(net "GND")
		)
		(pad "E3" smd circle
			(at -5.08 2.54 90)
			(size 0.635 0.635)
			(layers "F.Cu" "F.Mask" "F.Paste")
			(net "GND")
		)
		(pad "E4" smd circle
			(at -5.08 3.81 90)
			(size 0.635 0.635)
			(layers "F.Cu" "F.Mask" "F.Paste")
			(net "GND")
		)
		(pad "E5" smd circle
			(at -5.08 5.08 90)
			(size 0.635 0.635)
			(layers "F.Cu" "F.Mask" "F.Paste")
			(net "GND")
		)
		(pad "E6" smd circle
			(at -5.08 6.35 90)
			(size 0.635 0.635)
			(layers "F.Cu" "F.Mask" "F.Paste")
			(net "GND")
		)
		(pad "E7" smd circle
			(at -5.08 7.62 90)
			(size 0.635 0.635)
			(layers "F.Cu" "F.Mask" "F.Paste")
			(net "GND")
		)
		(pad "E8" smd circle
			(at -5.08 8.89 90)
			(size 0.635 0.635)
			(layers "F.Cu" "F.Mask" "F.Paste")
			(net "VSENSE_PVCCIOMCP_CPU1_SKT_VSEN")
		)
		(pad "E9" smd circle
			(at -5.08 10.16 90)
			(size 0.635 0.635)
			(layers "F.Cu" "F.Mask" "F.Paste")
			(net "GND")
		)
		(pad "E10" smd circle
			(at -5.08 11.43 90)
			(size 0.635 0.635)
			(layers "F.Cu" "F.Mask" "F.Paste")
			(net "VR_PVCCIOMCP_CPU1_XADDR1")
		)
		(pad "E11" smd circle
			(at -5.08 12.7 90)
			(size 0.635 0.635)
			(layers "F.Cu" "F.Mask" "F.Paste")
			(net "GND")
		)
		(pad "E12" smd circle
			(at -5.08 13.97 90)
			(size 0.635 0.635)
			(layers "F.Cu" "F.Mask" "F.Paste")
			(net "GND")
		)
		(pad "E13" smd circle
			(at -5.08 15.24 90)
			(size 0.635 0.635)
			(layers "F.Cu" "F.Mask" "F.Paste")
			(net "GND")
		)
		(pad "E14" smd circle
			(at -5.08 16.51 90)
			(size 0.635 0.635)
			(layers "F.Cu" "F.Mask" "F.Paste")
			(net "GND")
		)
		(pad "E15" smd circle
			(at -5.08 17.78 90)
			(size 0.635 0.635)
			(layers "F.Cu" "F.Mask" "F.Paste")
			(net "PVCCIOMCP_CPU1")
		)
		(pad "E16" smd circle
			(at -5.08 19.05 90)
			(size 0.635 0.635)
			(layers "F.Cu" "F.Mask" "F.Paste")
			(net "PVCCIOMCP_CPU1")
		)
		(pad "E17" smd circle
			(at -5.08 20.32 90)
			(size 0.635 0.635)
			(layers "F.Cu" "F.Mask" "F.Paste")
			(net "PVCCIOMCP_CPU1")
		)
		(pad "E18" smd circle
			(at -5.08 21.59 90)
			(size 0.635 0.635)
			(layers "F.Cu" "F.Mask" "F.Paste")
			(net "PVCCIOMCP_CPU1")
		)
		(pad "E19" smd circle
			(at -5.08 22.86 90)
			(size 0.635 0.635)
			(layers "F.Cu" "F.Mask" "F.Paste")
			(net "PVCCIOMCP_CPU1")
		)
		(pad "E20" smd circle
			(at -5.08 24.13 90)
			(size 0.635 0.635)
			(layers "F.Cu" "F.Mask" "F.Paste")
			(net "SVID_CLK1_CPU1_R")
		)
		(pad "F1" smd circle
			(at -6.35 0 90)
			(size 0.635 0.635)
			(layers "F.Cu" "F.Mask" "F.Paste")
			(net "PVCCIO_CPU1")
		)
		(pad "F2" smd circle
			(at -6.35 1.27 90)
			(size 0.635 0.635)
			(layers "F.Cu" "F.Mask" "F.Paste")
			(net "GND")
		)
		(pad "F3" smd circle
			(at -6.35 2.54 90)
			(size 0.635 0.635)
			(layers "F.Cu" "F.Mask" "F.Paste")
			(net "GND")
		)
		(pad "F4" smd circle
			(at -6.35 3.81 90)
			(size 0.635 0.635)
			(layers "F.Cu" "F.Mask" "F.Paste")
			(net "GND")
		)
		(pad "F5" smd circle
			(at -6.35 5.08 90)
			(size 0.635 0.635)
			(layers "F.Cu" "F.Mask" "F.Paste")
			(net "GND")
		)
		(pad "F6" smd circle
			(at -6.35 6.35 90)
			(size 0.635 0.635)
			(layers "F.Cu" "F.Mask" "F.Paste")
			(net "GND")
		)
		(pad "F7" smd circle
			(at -6.35 7.62 90)
			(size 0.635 0.635)
			(layers "F.Cu" "F.Mask" "F.Paste")
			(net "GND")
		)
		(pad "F8" smd circle
			(at -6.35 8.89 90)
			(size 0.635 0.635)
			(layers "F.Cu" "F.Mask" "F.Paste")
			(net "VSENSE_PVCCIOMCP_CPU1_SKT_VRTN")
		)
		(pad "F9" smd circle
			(at -6.35 10.16 90)
			(size 0.635 0.635)
			(layers "F.Cu" "F.Mask" "F.Paste")
			(net "GND")
		)
		(pad "F10" smd circle
			(at -6.35 11.43 90)
			(size 0.635 0.635)
			(layers "F.Cu" "F.Mask" "F.Paste")
			(net "VR_PVCCMCP_CPU1_XADDR2")
		)
		(pad "F11" smd circle
			(at -6.35 12.7 90)
			(size 0.635 0.635)
			(layers "F.Cu" "F.Mask" "F.Paste")
			(net "GND")
		)
		(pad "F12" smd circle
			(at -6.35 13.97 90)
			(size 0.635 0.635)
			(layers "F.Cu" "F.Mask" "F.Paste")
			(net "GND")
		)
		(pad "F13" smd circle
			(at -6.35 15.24 90)
			(size 0.635 0.635)
			(layers "F.Cu" "F.Mask" "F.Paste")
			(net "GND")
		)
		(pad "F14" smd circle
			(at -6.35 16.51 90)
			(size 0.635 0.635)
			(layers "F.Cu" "F.Mask" "F.Paste")
			(net "GND")
		)
		(pad "F15" smd circle
			(at -6.35 17.78 90)
			(size 0.635 0.635)
			(layers "F.Cu" "F.Mask" "F.Paste")
			(net "PVCCIOMCP_CPU1")
		)
		(pad "F16" smd circle
			(at -6.35 19.05 90)
			(size 0.635 0.635)
			(layers "F.Cu" "F.Mask" "F.Paste")
			(net "PVCCIOMCP_CPU1")
		)
		(pad "F17" smd circle
			(at -6.35 20.32 90)
			(size 0.635 0.635)
			(layers "F.Cu" "F.Mask" "F.Paste")
			(net "PVCCIOMCP_CPU1")
		)
		(pad "F18" smd circle
			(at -6.35 21.59 90)
			(size 0.635 0.635)
			(layers "F.Cu" "F.Mask" "F.Paste")
			(net "PVCCIOMCP_CPU1")
		)
		(pad "F19" smd circle
			(at -6.35 22.86 90)
			(size 0.635 0.635)
			(layers "F.Cu" "F.Mask" "F.Paste")
			(net "PVCCIOMCP_CPU1")
		)
		(pad "F20" smd circle
			(at -6.35 24.13 90)
			(size 0.635 0.635)
			(layers "F.Cu" "F.Mask" "F.Paste")
			(net "SVID_DIO1_CPU1_R")
		)
	)
)
